(kicad_pcb
	(version 20260206)
	(generator "pcbnew")
	(generator_version "10.0")
	(general
		(thickness 1.6)
		(legacy_teardrops no)
	)
	(paper "A4")
	(title_block
		(title "01162023_DA0F0TEBIF0_F0T_Expander_BD_F_brd_V02_OCP.brd")
		(comment 1 "Grand Teton / footprints 173-177 of 9728")
	)
	(layers
		(0 "F.Cu" signal "TOP")
		(4 "In1.Cu" signal "GND")
		(6 "In2.Cu" signal "VCC")
		(8 "In3.Cu" signal "VCC1")
		(10 "In4.Cu" signal "GND1")
		(12 "In5.Cu" signal "IN1")
		(14 "In6.Cu" signal "GND2")
		(16 "In7.Cu" signal "IN2")
		(18 "In8.Cu" signal "GND3")
		(20 "In9.Cu" signal "IN3")
		(22 "In10.Cu" signal "GND4")
		(24 "In11.Cu" signal "IN4")
		(26 "In12.Cu" signal "GND5")
		(28 "In13.Cu" signal "IN5")
		(30 "In14.Cu" signal "GND6")
		(32 "In15.Cu" signal "IN6")
		(34 "In16.Cu" signal "GND7")
		(2 "B.Cu" signal "BOTTOM")
		(9 "F.Adhes" user "F.Adhesive")
		(11 "B.Adhes" user "B.Adhesive")
		(13 "F.Paste" user "Package Geometry/Pastemask Top")
		(15 "B.Paste" user "Package Geometry/Pastemask Bottom")
		(5 "F.SilkS" user "Ref Des/Silkscreen Top")
		(7 "B.SilkS" user "Ref Des/Silkscreen Bottom")
		(1 "F.Mask" user "Board Geometry/Soldermask Top")
		(3 "B.Mask" user "Board Geometry/Soldermask Bottom")
		(17 "Dwgs.User" user "User.Drawings")
		(19 "Cmts.User" user "User.Comments")
		(21 "Eco1.User" user "User.Eco1")
		(23 "Eco2.User" user "User.Eco2")
		(25 "Edge.Cuts" user "Board Geometry/Outline")
		(27 "Margin" user)
		(31 "F.CrtYd" user "Package Geometry/Place Bound Top")
		(29 "B.CrtYd" user "Package Geometry/Place Bound Bottom")
		(35 "F.Fab" user "Ref Des/Assembly Top")
		(33 "B.Fab" user "Ref Des/Assembly Bottom")
	)
	(footprint ""
		(layer "F.Cu")
		(at 241.647218 -278.675846 90)
		(property "Reference" "C632"
			(at 0 0 90)
			(layer "F.SilkS")
			(hide yes)
			(effects
				(font
					(size 1.27 1.27)
				)
			)
		)
		(property "Value" ""
			(at 0 0 90)
			(layer "F.Fab")
			(effects
				(font
					(size 1.27 1.27)
				)
			)
		)
		(duplicate_pad_numbers_are_jumpers no)
		(fp_line
			(start 0.7874 -0.4064)
			(end 0.7874 0.4064)
			(stroke
				(width 0.1524)
				(type default)
			)
			(layer "F.SilkS")
		)
		(fp_line
			(start -0.7874 -0.4064)
			(end 0.7874 -0.4064)
			(stroke
				(width 0.1524)
				(type default)
			)
			(layer "F.SilkS")
		)
		(fp_line
			(start 0.7874 0.4064)
			(end -0.7874 0.4064)
			(stroke
				(width 0.1524)
				(type default)
			)
			(layer "F.SilkS")
		)
		(fp_line
			(start -0.7874 0.4064)
			(end -0.7874 -0.4064)
			(stroke
				(width 0.1524)
				(type default)
			)
			(layer "F.SilkS")
		)
		(fp_line
			(start -0.12065 -0.305054)
			(end -0.12065 -0.2794)
			(stroke
				(width 0.1)
				(type default)
			)
			(layer "F.Fab")
		)
		(fp_line
			(start -0.67945 -0.305054)
			(end -0.12065 -0.305054)
			(stroke
				(width 0.1)
				(type default)
			)
			(layer "F.Fab")
		)
		(fp_line
			(start 0.67945 -0.3048)
			(end 0.67945 0.3048)
			(stroke
				(width 0.1)
				(type default)
			)
			(layer "F.Fab")
		)
		(fp_line
			(start 0.12065 -0.3048)
			(end 0.67945 -0.3048)
			(stroke
				(width 0.1)
				(type default)
			)
			(layer "F.Fab")
		)
		(fp_line
			(start 0.12065 -0.2794)
			(end 0.12065 -0.3048)
			(stroke
				(width 0.1)
				(type default)
			)
			(layer "F.Fab")
		)
		(fp_line
			(start -0.12065 -0.2794)
			(end 0.12065 -0.2794)
			(stroke
				(width 0.1)
				(type default)
			)
			(layer "F.Fab")
		)
		(fp_line
			(start 0.120396 0.2794)
			(end -0.12065 0.2794)
			(stroke
				(width 0.1)
				(type default)
			)
			(layer "F.Fab")
		)
		(fp_line
			(start -0.12065 0.2794)
			(end -0.12065 0.3048)
			(stroke
				(width 0.1)
				(type default)
			)
			(layer "F.Fab")
		)
		(fp_line
			(start 0.67945 0.3048)
			(end 0.120396 0.3048)
			(stroke
				(width 0.1)
				(type default)
			)
			(layer "F.Fab")
		)
		(fp_line
			(start 0.120396 0.3048)
			(end 0.120396 0.2794)
			(stroke
				(width 0.1)
				(type default)
			)
			(layer "F.Fab")
		)
		(fp_line
			(start -0.12065 0.3048)
			(end -0.67945 0.3048)
			(stroke
				(width 0.1)
				(type default)
			)
			(layer "F.Fab")
		)
		(fp_line
			(start -0.67945 0.3048)
			(end -0.67945 -0.305054)
			(stroke
				(width 0.1)
				(type default)
			)
			(layer "F.Fab")
		)
		(pad "1" smd circle
			(at -0.40005 0 90)
			(size 0 0)
			(layers "F.Cu" "F.Mask" "F.Paste")
			(net "P1V25_PEX2_R")
		)
		(pad "2" smd circle
			(at 0.40005 0 90)
			(size 0 0)
			(layers "F.Cu" "F.Mask" "F.Paste")
			(net "GND")
		)
	)
	(footprint ""
		(layer "F.Cu")
		(at 404.943056 -373.76481 90)
		(property "Reference" "C3996"
			(at 0 0 90)
			(layer "F.SilkS")
			(hide yes)
			(effects
				(font
					(size 1.27 1.27)
				)
			)
		)
		(property "Value" ""
			(at 0 0 90)
			(layer "F.Fab")
			(effects
				(font
					(size 1.27 1.27)
				)
			)
		)
		(duplicate_pad_numbers_are_jumpers no)
		(fp_line
			(start 0.7874 -0.4064)
			(end 0.7874 0.4064)
			(stroke
				(width 0.1524)
				(type default)
			)
			(layer "F.SilkS")
		)
		(fp_line
			(start -0.7874 -0.4064)
			(end 0.7874 -0.4064)
			(stroke
				(width 0.1524)
				(type default)
			)
			(layer "F.SilkS")
		)
		(fp_line
			(start 0.7874 0.4064)
			(end -0.7874 0.4064)
			(stroke
				(width 0.1524)
				(type default)
			)
			(layer "F.SilkS")
		)
		(fp_line
			(start -0.7874 0.4064)
			(end -0.7874 -0.4064)
			(stroke
				(width 0.1524)
				(type default)
			)
			(layer "F.SilkS")
		)
		(fp_line
			(start -0.12065 -0.305054)
			(end -0.12065 -0.2794)
			(stroke
				(width 0.1)
				(type default)
			)
			(layer "F.Fab")
		)
		(fp_line
			(start -0.67945 -0.305054)
			(end -0.12065 -0.305054)
			(stroke
				(width 0.1)
				(type default)
			)
			(layer "F.Fab")
		)
		(fp_line
			(start 0.67945 -0.3048)
			(end 0.67945 0.3048)
			(stroke
				(width 0.1)
				(type default)
			)
			(layer "F.Fab")
		)
		(fp_line
			(start 0.12065 -0.3048)
			(end 0.67945 -0.3048)
			(stroke
				(width 0.1)
				(type default)
			)
			(layer "F.Fab")
		)
		(fp_line
			(start 0.12065 -0.2794)
			(end 0.12065 -0.3048)
			(stroke
				(width 0.1)
				(type default)
			)
			(layer "F.Fab")
		)
		(fp_line
			(start -0.12065 -0.2794)
			(end 0.12065 -0.2794)
			(stroke
				(width 0.1)
				(type default)
			)
			(layer "F.Fab")
		)
		(fp_line
			(start 0.120396 0.2794)
			(end -0.12065 0.2794)
			(stroke
				(width 0.1)
				(type default)
			)
			(layer "F.Fab")
		)
		(fp_line
			(start -0.12065 0.2794)
			(end -0.12065 0.3048)
			(stroke
				(width 0.1)
				(type default)
			)
			(layer "F.Fab")
		)
		(fp_line
			(start 0.67945 0.3048)
			(end 0.120396 0.3048)
			(stroke
				(width 0.1)
				(type default)
			)
			(layer "F.Fab")
		)
		(fp_line
			(start 0.120396 0.3048)
			(end 0.120396 0.2794)
			(stroke
				(width 0.1)
				(type default)
			)
			(layer "F.Fab")
		)
		(fp_line
			(start -0.12065 0.3048)
			(end -0.67945 0.3048)
			(stroke
				(width 0.1)
				(type default)
			)
			(layer "F.Fab")
		)
		(fp_line
			(start -0.67945 0.3048)
			(end -0.67945 -0.305054)
			(stroke
				(width 0.1)
				(type default)
			)
			(layer "F.Fab")
		)
		(pad "1" smd circle
			(at -0.40005 0 90)
			(size 0 0)
			(layers "F.Cu" "F.Mask" "F.Paste")
			(net "GND")
		)
		(pad "2" smd circle
			(at 0.40005 0 90)
			(size 0 0)
			(layers "F.Cu" "F.Mask" "F.Paste")
			(net "P3V3_AUX")
		)
	)
	(footprint ""
		(layer "F.Cu")
		(at 48.845978 -46.4439 180)
		(property "Reference" "U54"
			(at 0.128778 -2.40157 0)
			(unlocked yes)
			(layer "F.SilkS")
			(effects
				(font
					(size 0.7874 0.5842)
					(thickness 0.1524)
				)
			)
		)
		(property "Value" ""
			(at 0 0 180)
			(layer "F.Fab")
			(effects
				(font
					(size 1.27 1.27)
				)
			)
		)
		(duplicate_pad_numbers_are_jumpers no)
		(fp_line
			(start 1.500124 1.500124)
			(end 1.004062 1.500124)
			(stroke
				(width 0.1524)
				(type default)
			)
			(layer "F.SilkS")
		)
		(fp_line
			(start 1.500124 1.004062)
			(end 1.500124 1.500124)
			(stroke
				(width 0.1524)
				(type default)
			)
			(layer "F.SilkS")
		)
		(fp_line
			(start 1.500124 -1.500124)
			(end 1.500124 -1.004062)
			(stroke
				(width 0.1524)
				(type default)
			)
			(layer "F.SilkS")
		)
		(fp_line
			(start 1.004062 -1.500124)
			(end 1.500124 -1.500124)
			(stroke
				(width 0.1524)
				(type default)
			)
			(layer "F.SilkS")
		)
		(fp_line
			(start -1.004062 1.500124)
			(end -1.500124 1.500124)
			(stroke
				(width 0.1524)
				(type default)
			)
			(layer "F.SilkS")
		)
		(fp_line
			(start -1.500124 1.500124)
			(end -1.500124 1.004062)
			(stroke
				(width 0.1524)
				(type default)
			)
			(layer "F.SilkS")
		)
		(fp_line
			(start -1.500124 -1.004062)
			(end -1.500124 -1.500124)
			(stroke
				(width 0.1524)
				(type default)
			)
			(layer "F.SilkS")
		)
		(fp_line
			(start -1.500124 -1.500124)
			(end -1.004062 -1.500124)
			(stroke
				(width 0.1524)
				(type default)
			)
			(layer "F.SilkS")
		)
		(fp_poly
			(pts
				(xy -1.879346 -2.55905) (xy -2.597658 -1.840738) (xy -1.52019 -1.481328)
			)
			(stroke
				(width 0)
				(type default)
			)
			(fill yes)
			(layer "F.SilkS")
		)
		(fp_line
			(start 1.500124 1.500124)
			(end -1.500124 1.500124)
			(stroke
				(width 0.1)
				(type default)
			)
			(layer "F.Fab")
		)
		(fp_line
			(start 1.500124 -1.500124)
			(end 1.500124 1.500124)
			(stroke
				(width 0.1)
				(type default)
			)
			(layer "F.Fab")
		)
		(fp_line
			(start -1.500124 1.500124)
			(end -1.500124 -1.500124)
			(stroke
				(width 0.1)
				(type default)
			)
			(layer "F.Fab")
		)
		(fp_line
			(start -1.500124 -1.500124)
			(end 1.500124 -1.500124)
			(stroke
				(width 0.1)
				(type default)
			)
			(layer "F.Fab")
		)
		(fp_poly
			(pts
				(xy -2.847848 -1.258062) (xy -2.847848 -0.242062) (xy -1.831848 -0.750062)
			)
			(stroke
				(width 0)
				(type default)
			)
			(fill yes)
			(layer "F.Fab")
		)
		(pad "1" smd rect
			(at -1.400048 -0.750062 90)
			(size 0.2286 0.6096)
			(layers "F.Cu" "F.Mask" "F.Paste")
			(net "SSD1_ADC_A1")
		)
		(pad "2" smd rect
			(at -1.400048 -0.249936 90)
			(size 0.2286 0.6096)
			(layers "F.Cu" "F.Mask" "F.Paste")
			(net "SSD1_ADC_A0")
		)
		(pad "3" smd rect
			(at -1.400048 0.249936 90)
			(size 0.2286 0.6096)
			(layers "F.Cu" "F.Mask" "F.Paste")
			(net "SSD1_ADC_ALERT_N")
		)
		(pad "4" smd rect
			(at -1.400048 0.750062 90)
			(size 0.2286 0.6096)
			(layers "F.Cu" "F.Mask" "F.Paste")
			(net "SMB_SSD1_ADC_SDA")
		)
		(pad "5" smd rect
			(at -0.750062 1.400048 180)
			(size 0.2286 0.6096)
			(layers "F.Cu" "F.Mask" "F.Paste")
			(net "SMB_SSD1_ADC_SCL")
		)
		(pad "6" smd rect
			(at -0.249936 1.400048 180)
			(size 0.2286 0.6096)
			(layers "F.Cu" "F.Mask" "F.Paste")
			(net "Net_4615")
		)
		(pad "7" smd rect
			(at 0.249936 1.400048 180)
			(size 0.2286 0.6096)
			(layers "F.Cu" "F.Mask" "F.Paste")
			(net "Net_4616")
		)
		(pad "8" smd rect
			(at 0.750062 1.400048 180)
			(size 0.2286 0.6096)
			(layers "F.Cu" "F.Mask" "F.Paste")
			(net "Net_4617")
		)
		(pad "9" smd rect
			(at 1.400048 0.750062 90)
			(size 0.2286 0.6096)
			(layers "F.Cu" "F.Mask" "F.Paste")
			(net "P3V3_AUX")
		)
		(pad "10" smd rect
			(at 1.400048 0.249936 90)
			(size 0.2286 0.6096)
			(layers "F.Cu" "F.Mask" "F.Paste")
			(net "GND")
		)
		(pad "11" smd rect
			(at 1.400048 -0.249936 90)
			(size 0.2286 0.6096)
			(layers "F.Cu" "F.Mask" "F.Paste")
			(net "P12V_SSD1_R")
		)
		(pad "12" smd rect
			(at 1.400048 -0.750062 90)
			(size 0.2286 0.6096)
			(layers "F.Cu" "F.Mask" "F.Paste")
			(net "P12V_SSD1_VIN_N")
		)
		(pad "13" smd rect
			(at 0.750062 -1.400048 180)
			(size 0.2286 0.6096)
			(layers "F.Cu" "F.Mask" "F.Paste")
			(net "P12V_SSD1_VIN_P")
		)
		(pad "14" smd rect
			(at 0.249936 -1.400048 180)
			(size 0.2286 0.6096)
			(layers "F.Cu" "F.Mask" "F.Paste")
			(net "Net_4618")
		)
		(pad "15" smd rect
			(at -0.249936 -1.400048 180)
			(size 0.2286 0.6096)
			(layers "F.Cu" "F.Mask" "F.Paste")
			(net "Net_4619")
		)
		(pad "16" smd rect
			(at -0.750062 -1.400048 180)
			(size 0.2286 0.6096)
			(layers "F.Cu" "F.Mask" "F.Paste")
			(net "Net_4620")
		)
		(pad "TH" smd rect
			(at 0 0 180)
			(size 1.7018 1.7018)
			(layers "F.Cu" "F.Mask" "F.Paste")
			(net "GND")
		)
		(zone
			(layer "F.Cu")
			(hatch none 0.5)
			(connect_pads
				(clearance 0)
			)
			(min_thickness 0.25)
			(keepout
				(tracks not_allowed)
				(vias allowed)
				(pads allowed)
				(copperpour not_allowed)
				(footprints allowed)
			)
			(placement
				(enabled no)
				(sheetname "")
			)
			(fill
				(thermal_gap 0.5)
				(thermal_bridge_width 0.5)
				(island_removal_mode 0)
			)
			(polygon
				(pts
					(xy 49.890426 -46.4185) (xy 49.890426 -45.399452) (xy 47.80153 -45.399452) (xy 47.80153 -47.488348)
					(xy 49.890426 -47.488348) (xy 49.890426 -46.4439) (xy 49.747678 -46.4439) (xy 49.747678 -47.3456)
					(xy 47.944278 -47.3456) (xy 47.944278 -45.5422) (xy 49.747678 -45.5422) (xy 49.747678 -46.4185)
				)
			)
		)
	)
	(footprint ""
		(layer "F.Cu")
		(at 54.454806 -22.961346 90)
		(property "Reference" "R1634"
			(at 0 0 90)
			(layer "F.SilkS")
			(hide yes)
			(effects
				(font
					(size 1.27 1.27)
				)
			)
		)
		(property "Value" ""
			(at 0 0 90)
			(layer "F.Fab")
			(effects
				(font
					(size 1.27 1.27)
				)
			)
		)
		(duplicate_pad_numbers_are_jumpers no)
		(fp_line
			(start 0.7874 -0.4064)
			(end 0.7874 0.4064)
			(stroke
				(width 0.1524)
				(type default)
			)
			(layer "F.SilkS")
		)
		(fp_line
			(start -0.7874 -0.4064)
			(end 0.7874 -0.4064)
			(stroke
				(width 0.1524)
				(type default)
			)
			(layer "F.SilkS")
		)
		(fp_line
			(start 0.7874 0.4064)
			(end -0.7874 0.4064)
			(stroke
				(width 0.1524)
				(type default)
			)
			(layer "F.SilkS")
		)
		(fp_line
			(start -0.7874 0.4064)
			(end -0.7874 -0.4064)
			(stroke
				(width 0.1524)
				(type default)
			)
			(layer "F.SilkS")
		)
		(fp_line
			(start -0.12065 -0.305054)
			(end -0.12065 -0.2794)
			(stroke
				(width 0.1)
				(type default)
			)
			(layer "F.Fab")
		)
		(fp_line
			(start -0.67945 -0.305054)
			(end -0.12065 -0.305054)
			(stroke
				(width 0.1)
				(type default)
			)
			(layer "F.Fab")
		)
		(fp_line
			(start 0.67945 -0.3048)
			(end 0.67945 0.3048)
			(stroke
				(width 0.1)
				(type default)
			)
			(layer "F.Fab")
		)
		(fp_line
			(start 0.12065 -0.3048)
			(end 0.67945 -0.3048)
			(stroke
				(width 0.1)
				(type default)
			)
			(layer "F.Fab")
		)
		(fp_line
			(start 0.12065 -0.2794)
			(end 0.12065 -0.3048)
			(stroke
				(width 0.1)
				(type default)
			)
			(layer "F.Fab")
		)
		(fp_line
			(start -0.12065 -0.2794)
			(end 0.12065 -0.2794)
			(stroke
				(width 0.1)
				(type default)
			)
			(layer "F.Fab")
		)
		(fp_line
			(start 0.120396 0.2794)
			(end -0.12065 0.2794)
			(stroke
				(width 0.1)
				(type default)
			)
			(layer "F.Fab")
		)
		(fp_line
			(start -0.12065 0.2794)
			(end -0.12065 0.3048)
			(stroke
				(width 0.1)
				(type default)
			)
			(layer "F.Fab")
		)
		(fp_line
			(start 0.67945 0.3048)
			(end 0.120396 0.3048)
			(stroke
				(width 0.1)
				(type default)
			)
			(layer "F.Fab")
		)
		(fp_line
			(start 0.120396 0.3048)
			(end 0.120396 0.2794)
			(stroke
				(width 0.1)
				(type default)
			)
			(layer "F.Fab")
		)
		(fp_line
			(start -0.12065 0.3048)
			(end -0.67945 0.3048)
			(stroke
				(width 0.1)
				(type default)
			)
			(layer "F.Fab")
		)
		(fp_line
			(start -0.67945 0.3048)
			(end -0.67945 -0.305054)
			(stroke
				(width 0.1)
				(type default)
			)
			(layer "F.Fab")
		)
		(pad "1" smd circle
			(at -0.40005 0 90)
			(size 0 0)
			(layers "F.Cu" "F.Mask" "F.Paste")
			(net "SMB_SSD1_ISO_EN")
		)
		(pad "2" smd circle
			(at 0.40005 0 90)
			(size 0 0)
			(layers "F.Cu" "F.Mask" "F.Paste")
			(net "P3V3_AUX")
		)
	)
	(footprint ""
		(layer "F.Cu")
		(at 224.836482 -109.802422 180)
		(property "Reference" "PD83"
			(at 4.059682 2.210308 0)
			(unlocked yes)
			(layer "F.SilkS")
			(effects
				(font
					(size 0.7874 0.5842)
					(thickness 0.1524)
				)
				(justify left)
			)
		)
		(property "Value" ""
			(at 0 0 180)
			(layer "F.Fab")
			(effects
				(font
					(size 1.27 1.27)
				)
			)
		)
		(duplicate_pad_numbers_are_jumpers no)
		(fp_line
			(start 4.107942 1.459992)
			(end -3.400044 1.459992)
			(stroke
				(width 0.1524)
				(type default)
			)
			(layer "F.SilkS")
		)
		(fp_line
			(start 4.107942 -1.459992)
			(end 4.107942 1.459992)
			(stroke
				(width 0.1524)
				(type default)
			)
			(layer "F.SilkS")
		)
		(fp_line
			(start -3.400044 1.459992)
			(end -3.400044 -1.459992)
			(stroke
				(width 0.1524)
				(type default)
			)
			(layer "F.SilkS")
		)
		(fp_line
			(start -3.400044 -1.459992)
			(end 4.107942 -1.459992)
			(stroke
				(width 0.1524)
				(type default)
			)
			(layer "F.SilkS")
		)
		(fp_poly
			(pts
				(xy 4.107942 -1.459992) (xy 4.107942 1.459992) (xy 3.308096 1.459992) (xy 3.308096 -1.459992)
			)
			(stroke
				(width 0)
				(type default)
			)
			(fill yes)
			(layer "F.SilkS")
		)
		(fp_line
			(start 2.29997 1.459992)
			(end -2.29997 1.459992)
			(stroke
				(width 0.1)
				(type default)
			)
			(layer "F.Fab")
		)
		(fp_line
			(start 2.29997 -1.459992)
			(end 2.29997 1.459992)
			(stroke
				(width 0.1)
				(type default)
			)
			(layer "F.Fab")
		)
		(fp_line
			(start -2.29997 1.459992)
			(end -2.29997 -1.459992)
			(stroke
				(width 0.1)
				(type default)
			)
			(layer "F.Fab")
		)
		(fp_line
			(start -2.29997 -1.459992)
			(end 2.29997 -1.459992)
			(stroke
				(width 0.1)
				(type default)
			)
			(layer "F.Fab")
		)
		(fp_text user "-"
			(at 5.4102 0.29845 0)
			(unlocked yes)
			(layer "F.SilkS")
			(effects
				(font
					(size 1.905 1.4224)
					(thickness 0.1524)
				)
				(justify left)
			)
		)
		(fp_text user "+"
			(at -3.643122 -2.449322 180)
			(unlocked yes)
			(layer "F.SilkS")
			(effects
				(font
					(size 1.905 1.4224)
					(thickness 0.1524)
				)
				(justify left)
			)
		)
		(fp_text user "-"
			(at 5.4102 0.29845 0)
			(unlocked yes)
			(layer "F.Fab")
			(effects
				(font
					(size 1.905 1.4224)
					(thickness 0.1524)
				)
				(justify left)
			)
		)
		(fp_text user "+"
			(at -4.7752 -0.12065 180)
			(unlocked yes)
			(layer "F.Fab")
			(effects
				(font
					(size 1.905 1.4224)
					(thickness 0.1524)
				)
				(justify left)
			)
		)
		(pad "A" smd rect
			(at -1.999996 0 270)
			(size 1.7018 2.5146)
			(layers "F.Cu" "F.Mask" "F.Paste")
			(net "GND")
		)
		(pad "C" smd rect
			(at 1.999996 0 270)
			(size 1.7018 2.5146)
			(layers "F.Cu" "F.Mask" "F.Paste")
			(net "P12V_NIC3_R")
		)
	)
)
